# BASEBOARD_FAB2 (Tioga Pass) — schematic netlist excerpt (pin names and nets, part order shuffled) for the footprints in the layout excerpt that follows; sources: Cadence DE-HDL packaged netlist, KiCad conversion of Wiwynn_Tioga_Pass_MB.brd

R8W10  RES  0.0 5% CHIP  pkg 0402  page 245 : A = JTAG_RISER_TMS ; B = JTAG_PLD_TMS_MUX
C5L12  CAP_A  47UF 4V 20% X5R  pkg 0603V  page 220 : A = PVDDQ_DEF ; B = GND
R7M5  RES  20.0 1% CHIP  pkg 0402  page 99 : A = SMB_DDR_KLM_VPP_SDA_R ; B = SMB_DDR_KLM_VPP_SDA

(kicad_pcb
	(version 20260206)
	(generator "pcbnew")
	(generator_version "10.0")
	(general
		(thickness 1.6)
		(legacy_teardrops no)
	)
	(paper "A4")
	(title_block
		(title "Wiwynn_Tioga_Pass_MB.brd")
		(comment 1 "Tioga Pass / footprints 3438-3440 of 4770")
	)
	(layers
		(0 "F.Cu" signal "TOP")
		(4 "In1.Cu" signal "L2GND")
		(6 "In2.Cu" signal "L3")
		(8 "In3.Cu" signal "L4GND")
		(10 "In4.Cu" signal "L5")
		(12 "In5.Cu" signal "L6GND")
		(14 "In6.Cu" signal "L7VCC")
		(16 "In7.Cu" signal "L8VCC")
		(18 "In8.Cu" signal "L9GND")
		(20 "In9.Cu" signal "L10")
		(22 "In10.Cu" signal "L11GND")
		(24 "In11.Cu" signal "L12")
		(26 "In12.Cu" signal "L13GND")
		(2 "B.Cu" signal "BOTTOM")
		(9 "F.Adhes" user "F.Adhesive")
		(11 "B.Adhes" user "B.Adhesive")
		(13 "F.Paste" user "Package Geometry/Pastemask Top")
		(15 "B.Paste" user "Package Geometry/Pastemask Bottom")
		(5 "F.SilkS" user "Ref Des/Silkscreen Top")
		(7 "B.SilkS" user "Ref Des/Silkscreen Bottom")
		(1 "F.Mask" user "Board Geometry/Soldermask Top")
		(3 "B.Mask" user "Board Geometry/Soldermask Bottom")
		(17 "Dwgs.User" user "User.Drawings")
		(19 "Cmts.User" user "User.Comments")
		(21 "Eco1.User" user "User.Eco1")
		(23 "Eco2.User" user "User.Eco2")
		(25 "Edge.Cuts" user "Board Geometry/Outline")
		(27 "Margin" user)
		(31 "F.CrtYd" user "Package Geometry/Place Bound Top")
		(29 "B.CrtYd" user "Package Geometry/Place Bound Bottom")
		(35 "F.Fab" user "Ref Des/Assembly Top")
		(33 "B.Fab" user "Ref Des/Assembly Bottom")
	)
	(footprint ""
		(layer "B.Cu")
		(at 160.4264 -122.1994)
		(property "Reference" "R7M5"
			(at 0 0 0)
			(layer "B.SilkS")
			(hide yes)
			(effects
				(font
					(size 1.27 1.27)
				)
				(justify mirror)
			)
		)
		(property "Value" ""
			(at 0 0 0)
			(layer "B.Fab")
			(effects
				(font
					(size 1.27 1.27)
				)
				(justify mirror)
			)
		)
		(duplicate_pad_numbers_are_jumpers no)
		(fp_poly
			(pts
				(xy 0.2794 -0.1016) (xy -0.2794 -0.1016) (xy -0.2794 0.9906) (xy 0.2794 0.9906)
			)
			(stroke
				(width 0)
				(type default)
			)
			(fill no)
			(layer "B.CrtYd")
		)
		(fp_line
			(start -0.2794 -0.1016)
			(end 0.2794 -0.1016)
			(stroke
				(width 0.1)
				(type default)
			)
			(layer "B.Fab")
		)
		(fp_line
			(start -0.2794 0.9906)
			(end -0.2794 -0.1016)
			(stroke
				(width 0.1)
				(type default)
			)
			(layer "B.Fab")
		)
		(fp_line
			(start 0.2794 -0.1016)
			(end 0.2794 0.9906)
			(stroke
				(width 0.1)
				(type default)
			)
			(layer "B.Fab")
		)
		(fp_line
			(start 0.2794 0.9906)
			(end -0.2794 0.9906)
			(stroke
				(width 0.1)
				(type default)
			)
			(layer "B.Fab")
		)
		(pad "1" smd rect
			(at 0 0 180)
			(size 0.508 0.508)
			(layers "B.Cu" "B.Mask" "B.Paste")
			(net "SMB_DDR_KLM_VPP_SDA_R")
		)
		(pad "2" smd rect
			(at 0 0.889 180)
			(size 0.508 0.508)
			(layers "B.Cu" "B.Mask" "B.Paste")
			(net "SMB_DDR_KLM_VPP_SDA")
		)
		(zone
			(layer "B.Cu")
			(hatch none 0.5)
			(connect_pads
				(clearance 0)
			)
			(min_thickness 0.25)
			(keepout
				(tracks allowed)
				(vias not_allowed)
				(pads allowed)
				(copperpour not_allowed)
				(footprints allowed)
			)
			(placement
				(enabled no)
				(sheetname "")
			)
			(fill
				(thermal_gap 0.5)
				(thermal_bridge_width 0.5)
				(island_removal_mode 0)
			)
			(polygon
				(pts
					(xy 160.6804 -121.9454) (xy 160.1724 -121.9454) (xy 160.1724 -121.5644) (xy 160.6804 -121.5644)
				)
			)
		)
		(zone
			(layer "B.Cu")
			(hatch none 0.5)
			(connect_pads
				(clearance 0)
			)
			(min_thickness 0.25)
			(keepout
				(tracks not_allowed)
				(vias allowed)
				(pads allowed)
				(copperpour not_allowed)
				(footprints allowed)
			)
			(placement
				(enabled no)
				(sheetname "")
			)
			(fill
				(thermal_gap 0.5)
				(thermal_bridge_width 0.5)
				(island_removal_mode 0)
			)
			(polygon
				(pts
					(xy 160.6804 -121.5644) (xy 160.1724 -121.5644) (xy 160.1724 -121.9454) (xy 160.6804 -121.9454)
				)
			)
		)
	)
	(footprint ""
		(layer "B.Cu")
		(at 248.8565 -145.0086 -90)
		(property "Reference" "C5L12"
			(at -1.848866 0.752348 270)
			(unlocked yes)
			(layer "B.SilkS")
			(effects
				(font
					(size 1.27 0.9652)
					(thickness 0.1524)
				)
				(justify mirror)
			)
		)
		(property "Value" ""
			(at 0 0 90)
			(layer "B.Fab")
			(effects
				(font
					(size 1.27 1.27)
				)
				(justify mirror)
			)
		)
		(duplicate_pad_numbers_are_jumpers no)
		(fp_rect
			(start 0.500126 1.598422)
			(end -0.500126 -0.201422)
			(stroke
				(width 0)
				(type default)
			)
			(fill no)
			(layer "B.CrtYd")
		)
		(fp_line
			(start -0.500126 1.598422)
			(end 0.500126 1.598422)
			(stroke
				(width 0.1)
				(type default)
			)
			(layer "B.Fab")
		)
		(fp_line
			(start 0.500126 1.598422)
			(end 0.500126 -0.201422)
			(stroke
				(width 0.1)
				(type default)
			)
			(layer "B.Fab")
		)
		(fp_line
			(start -0.500126 -0.201422)
			(end -0.500126 1.598422)
			(stroke
				(width 0.1)
				(type default)
			)
			(layer "B.Fab")
		)
		(fp_line
			(start 0.500126 -0.201422)
			(end -0.500126 -0.201422)
			(stroke
				(width 0.1)
				(type default)
			)
			(layer "B.Fab")
		)
		(pad "1" smd rect
			(at 0 0 180)
			(size 0.889 0.9906)
			(layers "B.Cu" "B.Mask" "B.Paste")
			(net "PVDDQ_DEF")
		)
		(pad "2" smd rect
			(at 0 1.397 180)
			(size 0.889 0.9906)
			(layers "B.Cu" "B.Mask" "B.Paste")
			(net "GND")
		)
		(zone
			(layer "B.Cu")
			(hatch none 0.5)
			(connect_pads
				(clearance 0)
			)
			(min_thickness 0.25)
			(keepout
				(tracks not_allowed)
				(vias allowed)
				(pads allowed)
				(copperpour not_allowed)
				(footprints allowed)
			)
			(placement
				(enabled no)
				(sheetname "")
			)
			(fill
				(thermal_gap 0.5)
				(thermal_bridge_width 0.5)
				(island_removal_mode 0)
			)
			(polygon
				(pts
					(xy 247.904 -144.5133) (xy 248.412 -144.5133) (xy 248.412 -145.5039) (xy 247.904 -145.5039)
				)
			)
		)
		(zone
			(layer "B.Cu")
			(hatch none 0.5)
			(connect_pads
				(clearance 0)
			)
			(min_thickness 0.25)
			(keepout
				(tracks allowed)
				(vias not_allowed)
				(pads allowed)
				(copperpour not_allowed)
				(footprints allowed)
			)
			(placement
				(enabled no)
				(sheetname "")
			)
			(fill
				(thermal_gap 0.5)
				(thermal_bridge_width 0.5)
				(island_removal_mode 0)
			)
			(polygon
				(pts
					(xy 247.904 -144.5133) (xy 248.412 -144.5133) (xy 248.412 -145.5039) (xy 247.904 -145.5039)
				)
			)
		)
	)
	(footprint ""
		(layer "B.Cu")
		(at 359.8672 -4.2418 180)
		(property "Reference" "R8W10"
			(at 0.8382 -0.67818 180)
			(unlocked yes)
			(layer "B.SilkS")
			(effects
				(font
					(size 0.4064 0.254)
					(thickness 0.1524)
				)
				(justify left mirror)
			)
		)
		(property "Value" ""
			(at 0 0 0)
			(layer "B.Fab")
			(effects
				(font
					(size 1.27 1.27)
				)
				(justify mirror)
			)
		)
		(duplicate_pad_numbers_are_jumpers no)
		(fp_poly
			(pts
				(xy 0.2794 -0.1016) (xy -0.2794 -0.1016) (xy -0.2794 0.9906) (xy 0.2794 0.9906)
			)
			(stroke
				(width 0)
				(type default)
			)
			(fill no)
			(layer "B.CrtYd")
		)
		(fp_line
			(start 0.2794 0.9906)
			(end -0.2794 0.9906)
			(stroke
				(width 0.1)
				(type default)
			)
			(layer "B.Fab")
		)
		(fp_line
			(start 0.2794 -0.1016)
			(end 0.2794 0.9906)
			(stroke
				(width 0.1)
				(type default)
			)
			(layer "B.Fab")
		)
		(fp_line
			(start -0.2794 0.9906)
			(end -0.2794 -0.1016)
			(stroke
				(width 0.1)
				(type default)
			)
			(layer "B.Fab")
		)
		(fp_line
			(start -0.2794 -0.1016)
			(end 0.2794 -0.1016)
			(stroke
				(width 0.1)
				(type default)
			)
			(layer "B.Fab")
		)
		(pad "1" smd rect
			(at 0 0)
			(size 0.508 0.508)
			(layers "B.Cu" "B.Mask" "B.Paste")
			(net "JTAG_RISER_TMS")
		)
		(pad "2" smd rect
			(at 0 0.889)
			(size 0.508 0.508)
			(layers "B.Cu" "B.Mask" "B.Paste")
			(net "JTAG_PLD_TMS_MUX")
		)
		(zone
			(layer "B.Cu")
			(hatch none 0.5)
			(connect_pads
				(clearance 0)
			)
			(min_thickness 0.25)
			(keepout
				(tracks not_allowed)
				(vias allowed)
				(pads allowed)
				(copperpour not_allowed)
				(footprints allowed)
			)
			(placement
				(enabled no)
				(sheetname "")
			)
			(fill
				(thermal_gap 0.5)
				(thermal_bridge_width 0.5)
				(island_removal_mode 0)
			)
			(polygon
				(pts
					(xy 359.6132 -4.8768) (xy 360.1212 -4.8768) (xy 360.1212 -4.4958) (xy 359.6132 -4.4958)
				)
			)
		)
		(zone
			(layer "B.Cu")
			(hatch none 0.5)
			(connect_pads
				(clearance 0)
			)
			(min_thickness 0.25)
			(keepout
				(tracks allowed)
				(vias not_allowed)
				(pads allowed)
				(copperpour not_allowed)
				(footprints allowed)
			)
			(placement
				(enabled no)
				(sheetname "")
			)
			(fill
				(thermal_gap 0.5)
				(thermal_bridge_width 0.5)
				(island_removal_mode 0)
			)
			(polygon
				(pts
					(xy 359.6132 -4.4958) (xy 360.1212 -4.4958) (xy 360.1212 -4.8768) (xy 359.6132 -4.8768)
				)
			)
		)
	)
)
